(kicad_pcb
	(version 20260206)
	(generator "pcbnew")
	(generator_version "10.0")
	(general
		(thickness 1.6)
		(legacy_teardrops no)
	)
	(paper "A4")
	(title_block
		(title "04192023_DAF0TMB3IC0_F0TG_MB_C_brd_V02_OCP.brd")
		(comment 1 "Grand Teton / footprints 3249-3254 of 8354")
	)
	(layers
		(0 "F.Cu" signal "TOP")
		(4 "In1.Cu" signal "GND")
		(6 "In2.Cu" signal "IN1")
		(8 "In3.Cu" signal "GND1")
		(10 "In4.Cu" signal "IN2")
		(12 "In5.Cu" signal "GND2")
		(14 "In6.Cu" signal "IN3")
		(16 "In7.Cu" signal "GND3")
		(18 "In8.Cu" signal "VCC")
		(20 "In9.Cu" signal "VCC1")
		(22 "In10.Cu" signal "GND4")
		(24 "In11.Cu" signal "IN4")
		(26 "In12.Cu" signal "GND5")
		(28 "In13.Cu" signal "IN5")
		(30 "In14.Cu" signal "GND6")
		(32 "In15.Cu" signal "IN6")
		(34 "In16.Cu" signal "GND7")
		(2 "B.Cu" signal "BOTTOM")
		(9 "F.Adhes" user "F.Adhesive")
		(11 "B.Adhes" user "B.Adhesive")
		(13 "F.Paste" user "Package Geometry/Pastemask Top")
		(15 "B.Paste" user "Package Geometry/Pastemask Bottom")
		(5 "F.SilkS" user "Ref Des/Silkscreen Top")
		(7 "B.SilkS" user "Ref Des/Silkscreen Bottom")
		(1 "F.Mask" user "Board Geometry/Soldermask Top")
		(3 "B.Mask" user "Board Geometry/Soldermask Bottom")
		(17 "Dwgs.User" user "User.Drawings")
		(19 "Cmts.User" user "User.Comments")
		(21 "Eco1.User" user "User.Eco1")
		(23 "Eco2.User" user "User.Eco2")
		(25 "Edge.Cuts" user "Board Geometry/Outline")
		(27 "Margin" user)
		(31 "F.CrtYd" user "Package Geometry/Place Bound Top")
		(29 "B.CrtYd" user "Package Geometry/Place Bound Bottom")
		(35 "F.Fab" user "Ref Des/Assembly Top")
		(33 "B.Fab" user "Ref Des/Assembly Bottom")
	)
	(footprint ""
		(layer "F.Cu")
		(at 145.669 -117.348)
		(property "Reference" "R8122"
			(at 0 0 0)
			(layer "F.SilkS")
			(hide yes)
			(effects
				(font
					(size 1.27 1.27)
				)
			)
		)
		(property "Value" ""
			(at 0 0 0)
			(layer "F.Fab")
			(effects
				(font
					(size 1.27 1.27)
				)
			)
		)
		(duplicate_pad_numbers_are_jumpers no)
		(fp_line
			(start -0.7874 -0.4064)
			(end 0.7874 -0.4064)
			(stroke
				(width 0.1524)
				(type default)
			)
			(layer "F.SilkS")
		)
		(fp_line
			(start -0.7874 0.4064)
			(end -0.7874 -0.4064)
			(stroke
				(width 0.1524)
				(type default)
			)
			(layer "F.SilkS")
		)
		(fp_line
			(start 0.7874 -0.4064)
			(end 0.7874 0.4064)
			(stroke
				(width 0.1524)
				(type default)
			)
			(layer "F.SilkS")
		)
		(fp_line
			(start 0.7874 0.4064)
			(end -0.7874 0.4064)
			(stroke
				(width 0.1524)
				(type default)
			)
			(layer "F.SilkS")
		)
		(fp_line
			(start -0.67945 -0.305054)
			(end -0.12065 -0.305054)
			(stroke
				(width 0.1)
				(type default)
			)
			(layer "F.Fab")
		)
		(fp_line
			(start -0.67945 0.3048)
			(end -0.67945 -0.305054)
			(stroke
				(width 0.1)
				(type default)
			)
			(layer "F.Fab")
		)
		(fp_line
			(start -0.12065 -0.305054)
			(end -0.12065 -0.2794)
			(stroke
				(width 0.1)
				(type default)
			)
			(layer "F.Fab")
		)
		(fp_line
			(start -0.12065 -0.2794)
			(end 0.12065 -0.2794)
			(stroke
				(width 0.1)
				(type default)
			)
			(layer "F.Fab")
		)
		(fp_line
			(start -0.12065 0.2794)
			(end -0.12065 0.3048)
			(stroke
				(width 0.1)
				(type default)
			)
			(layer "F.Fab")
		)
		(fp_line
			(start -0.12065 0.3048)
			(end -0.67945 0.3048)
			(stroke
				(width 0.1)
				(type default)
			)
			(layer "F.Fab")
		)
		(fp_line
			(start 0.120396 0.2794)
			(end -0.12065 0.2794)
			(stroke
				(width 0.1)
				(type default)
			)
			(layer "F.Fab")
		)
		(fp_line
			(start 0.120396 0.3048)
			(end 0.120396 0.2794)
			(stroke
				(width 0.1)
				(type default)
			)
			(layer "F.Fab")
		)
		(fp_line
			(start 0.12065 -0.3048)
			(end 0.67945 -0.3048)
			(stroke
				(width 0.1)
				(type default)
			)
			(layer "F.Fab")
		)
		(fp_line
			(start 0.12065 -0.2794)
			(end 0.12065 -0.3048)
			(stroke
				(width 0.1)
				(type default)
			)
			(layer "F.Fab")
		)
		(fp_line
			(start 0.67945 -0.3048)
			(end 0.67945 0.3048)
			(stroke
				(width 0.1)
				(type default)
			)
			(layer "F.Fab")
		)
		(fp_line
			(start 0.67945 0.3048)
			(end 0.120396 0.3048)
			(stroke
				(width 0.1)
				(type default)
			)
			(layer "F.Fab")
		)
		(pad "1" smd circle
			(at -0.40005 0)
			(size 0 0)
			(layers "F.Cu" "F.Mask" "F.Paste")
			(net "P12V_AUX_UV_TRIGGER")
		)
		(pad "2" smd circle
			(at 0.40005 0)
			(size 0 0)
			(layers "F.Cu" "F.Mask" "F.Paste")
			(net "GND")
		)
	)
	(footprint ""
		(layer "F.Cu")
		(at 310.411876 -70.098412 90)
		(property "Reference" "D93"
			(at -3.934714 -0.691642 90)
			(unlocked yes)
			(layer "F.SilkS")
			(effects
				(font
					(size 0.7874 0.5842)
					(thickness 0.1524)
				)
				(justify left)
			)
		)
		(property "Value" ""
			(at 0 0 90)
			(layer "F.Fab")
			(effects
				(font
					(size 1.27 1.27)
				)
			)
		)
		(duplicate_pad_numbers_are_jumpers no)
		(fp_line
			(start 1.16078 -0.4826)
			(end 1.16078 0.4826)
			(stroke
				(width 0.1524)
				(type default)
			)
			(layer "F.SilkS")
		)
		(fp_line
			(start 1.03378 -0.4826)
			(end 1.03378 0.4826)
			(stroke
				(width 0.1524)
				(type default)
			)
			(layer "F.SilkS")
		)
		(fp_line
			(start 0.90678 -0.4826)
			(end 0.90678 0.4826)
			(stroke
				(width 0.1524)
				(type default)
			)
			(layer "F.SilkS")
		)
		(fp_line
			(start -0.64008 -0.4826)
			(end 1.16078 -0.4826)
			(stroke
				(width 0.1524)
				(type default)
			)
			(layer "F.SilkS")
		)
		(fp_line
			(start -0.79248 -0.4826)
			(end 1.03378 -0.4826)
			(stroke
				(width 0.1524)
				(type default)
			)
			(layer "F.SilkS")
		)
		(fp_line
			(start -0.89408 -0.4826)
			(end 0.90678 -0.4826)
			(stroke
				(width 0.1524)
				(type default)
			)
			(layer "F.SilkS")
		)
		(fp_line
			(start 1.16078 0.4826)
			(end -0.64008 0.4826)
			(stroke
				(width 0.1524)
				(type default)
			)
			(layer "F.SilkS")
		)
		(fp_line
			(start 1.03378 0.4826)
			(end -0.79248 0.4826)
			(stroke
				(width 0.1524)
				(type default)
			)
			(layer "F.SilkS")
		)
		(fp_line
			(start 0.90678 0.4826)
			(end -0.90678 0.4826)
			(stroke
				(width 0.1524)
				(type default)
			)
			(layer "F.SilkS")
		)
		(fp_line
			(start -0.90678 0.4826)
			(end -0.90678 -0.4699)
			(stroke
				(width 0.1524)
				(type default)
			)
			(layer "F.SilkS")
		)
		(fp_line
			(start 0.499872 -0.249936)
			(end 0.499872 0.249936)
			(stroke
				(width 0.1)
				(type default)
			)
			(layer "F.Fab")
		)
		(fp_line
			(start -0.499872 -0.249936)
			(end 0.499872 -0.249936)
			(stroke
				(width 0.1)
				(type default)
			)
			(layer "F.Fab")
		)
		(fp_line
			(start 0.499872 0.249936)
			(end -0.499872 0.249936)
			(stroke
				(width 0.1)
				(type default)
			)
			(layer "F.Fab")
		)
		(fp_line
			(start -0.499872 0.249936)
			(end -0.499872 -0.249936)
			(stroke
				(width 0.1)
				(type default)
			)
			(layer "F.Fab")
		)
		(pad "A" smd rect
			(at -0.47498 0 90)
			(size 0.6096 0.7112)
			(layers "F.Cu" "F.Mask" "F.Paste")
			(net "LED_RST_RSMRST_PLD_R_N")
		)
		(pad "C" smd rect
			(at 0.47498 0 90)
			(size 0.6096 0.7112)
			(layers "F.Cu" "F.Mask" "F.Paste")
			(net "LED_RST_RSMRST_PLD_R_N_D")
		)
	)
	(footprint ""
		(layer "F.Cu")
		(at 391.291318 -77.423264)
		(property "Reference" "R1306"
			(at 0 0 0)
			(layer "F.SilkS")
			(hide yes)
			(effects
				(font
					(size 1.27 1.27)
				)
			)
		)
		(property "Value" ""
			(at 0 0 0)
			(layer "F.Fab")
			(effects
				(font
					(size 1.27 1.27)
				)
			)
		)
		(duplicate_pad_numbers_are_jumpers no)
		(fp_line
			(start -0.7874 -0.4064)
			(end 0.7874 -0.4064)
			(stroke
				(width 0.1524)
				(type default)
			)
			(layer "F.SilkS")
		)
		(fp_line
			(start -0.7874 0.4064)
			(end -0.7874 -0.4064)
			(stroke
				(width 0.1524)
				(type default)
			)
			(layer "F.SilkS")
		)
		(fp_line
			(start 0.7874 -0.4064)
			(end 0.7874 0.4064)
			(stroke
				(width 0.1524)
				(type default)
			)
			(layer "F.SilkS")
		)
		(fp_line
			(start 0.7874 0.4064)
			(end -0.7874 0.4064)
			(stroke
				(width 0.1524)
				(type default)
			)
			(layer "F.SilkS")
		)
		(fp_line
			(start -0.67945 -0.305054)
			(end -0.12065 -0.305054)
			(stroke
				(width 0.1)
				(type default)
			)
			(layer "F.Fab")
		)
		(fp_line
			(start -0.67945 0.3048)
			(end -0.67945 -0.305054)
			(stroke
				(width 0.1)
				(type default)
			)
			(layer "F.Fab")
		)
		(fp_line
			(start -0.12065 -0.305054)
			(end -0.12065 -0.2794)
			(stroke
				(width 0.1)
				(type default)
			)
			(layer "F.Fab")
		)
		(fp_line
			(start -0.12065 -0.2794)
			(end 0.12065 -0.2794)
			(stroke
				(width 0.1)
				(type default)
			)
			(layer "F.Fab")
		)
		(fp_line
			(start -0.12065 0.2794)
			(end -0.12065 0.3048)
			(stroke
				(width 0.1)
				(type default)
			)
			(layer "F.Fab")
		)
		(fp_line
			(start -0.12065 0.3048)
			(end -0.67945 0.3048)
			(stroke
				(width 0.1)
				(type default)
			)
			(layer "F.Fab")
		)
		(fp_line
			(start 0.120396 0.2794)
			(end -0.12065 0.2794)
			(stroke
				(width 0.1)
				(type default)
			)
			(layer "F.Fab")
		)
		(fp_line
			(start 0.120396 0.3048)
			(end 0.120396 0.2794)
			(stroke
				(width 0.1)
				(type default)
			)
			(layer "F.Fab")
		)
		(fp_line
			(start 0.12065 -0.3048)
			(end 0.67945 -0.3048)
			(stroke
				(width 0.1)
				(type default)
			)
			(layer "F.Fab")
		)
		(fp_line
			(start 0.12065 -0.2794)
			(end 0.12065 -0.3048)
			(stroke
				(width 0.1)
				(type default)
			)
			(layer "F.Fab")
		)
		(fp_line
			(start 0.67945 -0.3048)
			(end 0.67945 0.3048)
			(stroke
				(width 0.1)
				(type default)
			)
			(layer "F.Fab")
		)
		(fp_line
			(start 0.67945 0.3048)
			(end 0.120396 0.3048)
			(stroke
				(width 0.1)
				(type default)
			)
			(layer "F.Fab")
		)
		(pad "1" smd circle
			(at -0.40005 0)
			(size 0 0)
			(layers "F.Cu" "F.Mask" "F.Paste")
			(net "GND")
		)
		(pad "2" smd circle
			(at 0.40005 0)
			(size 0 0)
			(layers "F.Cu" "F.Mask" "F.Paste")
			(net "INA230_6_A1")
		)
	)
	(footprint ""
		(layer "F.Cu")
		(at 191.52362 -421.026082 90)
		(property "Reference" "C1775"
			(at 0 0 90)
			(layer "F.SilkS")
			(hide yes)
			(effects
				(font
					(size 1.27 1.27)
				)
			)
		)
		(property "Value" ""
			(at 0 0 90)
			(layer "F.Fab")
			(effects
				(font
					(size 1.27 1.27)
				)
			)
		)
		(duplicate_pad_numbers_are_jumpers no)
		(fp_line
			(start 0.7874 -0.4064)
			(end 0.7874 0.4064)
			(stroke
				(width 0.1524)
				(type default)
			)
			(layer "F.SilkS")
		)
		(fp_line
			(start -0.7874 -0.4064)
			(end 0.7874 -0.4064)
			(stroke
				(width 0.1524)
				(type default)
			)
			(layer "F.SilkS")
		)
		(fp_line
			(start 0.7874 0.4064)
			(end -0.7874 0.4064)
			(stroke
				(width 0.1524)
				(type default)
			)
			(layer "F.SilkS")
		)
		(fp_line
			(start -0.7874 0.4064)
			(end -0.7874 -0.4064)
			(stroke
				(width 0.1524)
				(type default)
			)
			(layer "F.SilkS")
		)
		(fp_line
			(start -0.12065 -0.305054)
			(end -0.12065 -0.2794)
			(stroke
				(width 0.1)
				(type default)
			)
			(layer "F.Fab")
		)
		(fp_line
			(start -0.67945 -0.305054)
			(end -0.12065 -0.305054)
			(stroke
				(width 0.1)
				(type default)
			)
			(layer "F.Fab")
		)
		(fp_line
			(start 0.67945 -0.3048)
			(end 0.67945 0.3048)
			(stroke
				(width 0.1)
				(type default)
			)
			(layer "F.Fab")
		)
		(fp_line
			(start 0.12065 -0.3048)
			(end 0.67945 -0.3048)
			(stroke
				(width 0.1)
				(type default)
			)
			(layer "F.Fab")
		)
		(fp_line
			(start 0.12065 -0.2794)
			(end 0.12065 -0.3048)
			(stroke
				(width 0.1)
				(type default)
			)
			(layer "F.Fab")
		)
		(fp_line
			(start -0.12065 -0.2794)
			(end 0.12065 -0.2794)
			(stroke
				(width 0.1)
				(type default)
			)
			(layer "F.Fab")
		)
		(fp_line
			(start 0.120396 0.2794)
			(end -0.12065 0.2794)
			(stroke
				(width 0.1)
				(type default)
			)
			(layer "F.Fab")
		)
		(fp_line
			(start -0.12065 0.2794)
			(end -0.12065 0.3048)
			(stroke
				(width 0.1)
				(type default)
			)
			(layer "F.Fab")
		)
		(fp_line
			(start 0.67945 0.3048)
			(end 0.120396 0.3048)
			(stroke
				(width 0.1)
				(type default)
			)
			(layer "F.Fab")
		)
		(fp_line
			(start 0.120396 0.3048)
			(end 0.120396 0.2794)
			(stroke
				(width 0.1)
				(type default)
			)
			(layer "F.Fab")
		)
		(fp_line
			(start -0.12065 0.3048)
			(end -0.67945 0.3048)
			(stroke
				(width 0.1)
				(type default)
			)
			(layer "F.Fab")
		)
		(fp_line
			(start -0.67945 0.3048)
			(end -0.67945 -0.305054)
			(stroke
				(width 0.1)
				(type default)
			)
			(layer "F.Fab")
		)
		(pad "1" smd circle
			(at -0.40005 0 90)
			(size 0 0)
			(layers "F.Cu" "F.Mask" "F.Paste")
			(net "P3V3_AUX")
		)
		(pad "2" smd circle
			(at 0.40005 0 90)
			(size 0 0)
			(layers "F.Cu" "F.Mask" "F.Paste")
			(net "GND")
		)
	)
	(footprint ""
		(layer "F.Cu")
		(at 302.241458 -116.891308 180)
		(property "Reference" "R714"
			(at 0 0 180)
			(layer "F.SilkS")
			(hide yes)
			(effects
				(font
					(size 1.27 1.27)
				)
			)
		)
		(property "Value" ""
			(at 0 0 180)
			(layer "F.Fab")
			(effects
				(font
					(size 1.27 1.27)
				)
			)
		)
		(duplicate_pad_numbers_are_jumpers no)
		(fp_line
			(start 0.7874 0.4064)
			(end -0.7874 0.4064)
			(stroke
				(width 0.1524)
				(type default)
			)
			(layer "F.SilkS")
		)
		(fp_line
			(start 0.7874 -0.4064)
			(end 0.7874 0.4064)
			(stroke
				(width 0.1524)
				(type default)
			)
			(layer "F.SilkS")
		)
		(fp_line
			(start -0.7874 0.4064)
			(end -0.7874 -0.4064)
			(stroke
				(width 0.1524)
				(type default)
			)
			(layer "F.SilkS")
		)
		(fp_line
			(start -0.7874 -0.4064)
			(end 0.7874 -0.4064)
			(stroke
				(width 0.1524)
				(type default)
			)
			(layer "F.SilkS")
		)
		(fp_line
			(start 0.67945 0.3048)
			(end 0.120396 0.3048)
			(stroke
				(width 0.1)
				(type default)
			)
			(layer "F.Fab")
		)
		(fp_line
			(start 0.67945 -0.3048)
			(end 0.67945 0.3048)
			(stroke
				(width 0.1)
				(type default)
			)
			(layer "F.Fab")
		)
		(fp_line
			(start 0.12065 -0.2794)
			(end 0.12065 -0.3048)
			(stroke
				(width 0.1)
				(type default)
			)
			(layer "F.Fab")
		)
		(fp_line
			(start 0.12065 -0.3048)
			(end 0.67945 -0.3048)
			(stroke
				(width 0.1)
				(type default)
			)
			(layer "F.Fab")
		)
		(fp_line
			(start 0.120396 0.3048)
			(end 0.120396 0.2794)
			(stroke
				(width 0.1)
				(type default)
			)
			(layer "F.Fab")
		)
		(fp_line
			(start 0.120396 0.2794)
			(end -0.12065 0.2794)
			(stroke
				(width 0.1)
				(type default)
			)
			(layer "F.Fab")
		)
		(fp_line
			(start -0.12065 0.3048)
			(end -0.67945 0.3048)
			(stroke
				(width 0.1)
				(type default)
			)
			(layer "F.Fab")
		)
		(fp_line
			(start -0.12065 0.2794)
			(end -0.12065 0.3048)
			(stroke
				(width 0.1)
				(type default)
			)
			(layer "F.Fab")
		)
		(fp_line
			(start -0.12065 -0.2794)
			(end 0.12065 -0.2794)
			(stroke
				(width 0.1)
				(type default)
			)
			(layer "F.Fab")
		)
		(fp_line
			(start -0.12065 -0.305054)
			(end -0.12065 -0.2794)
			(stroke
				(width 0.1)
				(type default)
			)
			(layer "F.Fab")
		)
		(fp_line
			(start -0.67945 0.3048)
			(end -0.67945 -0.305054)
			(stroke
				(width 0.1)
				(type default)
			)
			(layer "F.Fab")
		)
		(fp_line
			(start -0.67945 -0.305054)
			(end -0.12065 -0.305054)
			(stroke
				(width 0.1)
				(type default)
			)
			(layer "F.Fab")
		)
		(pad "1" smd circle
			(at -0.40005 0 180)
			(size 0 0)
			(layers "F.Cu" "F.Mask" "F.Paste")
			(net "MB_FRU_ADDR2")
		)
		(pad "2" smd circle
			(at 0.40005 0 180)
			(size 0 0)
			(layers "F.Cu" "F.Mask" "F.Paste")
			(net "GND")
		)
	)
	(footprint ""
		(layer "F.Cu")
		(at 96.21266 -339.681058 90)
		(property "Reference" "PR272"
			(at 0 0 90)
			(layer "F.SilkS")
			(hide yes)
			(effects
				(font
					(size 1.27 1.27)
				)
			)
		)
		(property "Value" ""
			(at 0 0 90)
			(layer "F.Fab")
			(effects
				(font
					(size 1.27 1.27)
				)
			)
		)
		(duplicate_pad_numbers_are_jumpers no)
		(fp_line
			(start 0.7874 -0.4064)
			(end 0.7874 0.4064)
			(stroke
				(width 0.1524)
				(type default)
			)
			(layer "F.SilkS")
		)
		(fp_line
			(start -0.7874 -0.4064)
			(end 0.7874 -0.4064)
			(stroke
				(width 0.1524)
				(type default)
			)
			(layer "F.SilkS")
		)
		(fp_line
			(start 0.7874 0.4064)
			(end -0.7874 0.4064)
			(stroke
				(width 0.1524)
				(type default)
			)
			(layer "F.SilkS")
		)
		(fp_line
			(start -0.7874 0.4064)
			(end -0.7874 -0.4064)
			(stroke
				(width 0.1524)
				(type default)
			)
			(layer "F.SilkS")
		)
		(fp_line
			(start -0.12065 -0.305054)
			(end -0.12065 -0.2794)
			(stroke
				(width 0.1)
				(type default)
			)
			(layer "F.Fab")
		)
		(fp_line
			(start -0.67945 -0.305054)
			(end -0.12065 -0.305054)
			(stroke
				(width 0.1)
				(type default)
			)
			(layer "F.Fab")
		)
		(fp_line
			(start 0.67945 -0.3048)
			(end 0.67945 0.3048)
			(stroke
				(width 0.1)
				(type default)
			)
			(layer "F.Fab")
		)
		(fp_line
			(start 0.12065 -0.3048)
			(end 0.67945 -0.3048)
			(stroke
				(width 0.1)
				(type default)
			)
			(layer "F.Fab")
		)
		(fp_line
			(start 0.12065 -0.2794)
			(end 0.12065 -0.3048)
			(stroke
				(width 0.1)
				(type default)
			)
			(layer "F.Fab")
		)
		(fp_line
			(start -0.12065 -0.2794)
			(end 0.12065 -0.2794)
			(stroke
				(width 0.1)
				(type default)
			)
			(layer "F.Fab")
		)
		(fp_line
			(start 0.120396 0.2794)
			(end -0.12065 0.2794)
			(stroke
				(width 0.1)
				(type default)
			)
			(layer "F.Fab")
		)
		(fp_line
			(start -0.12065 0.2794)
			(end -0.12065 0.3048)
			(stroke
				(width 0.1)
				(type default)
			)
			(layer "F.Fab")
		)
		(fp_line
			(start 0.67945 0.3048)
			(end 0.120396 0.3048)
			(stroke
				(width 0.1)
				(type default)
			)
			(layer "F.Fab")
		)
		(fp_line
			(start 0.120396 0.3048)
			(end 0.120396 0.2794)
			(stroke
				(width 0.1)
				(type default)
			)
			(layer "F.Fab")
		)
		(fp_line
			(start -0.12065 0.3048)
			(end -0.67945 0.3048)
			(stroke
				(width 0.1)
				(type default)
			)
			(layer "F.Fab")
		)
		(fp_line
			(start -0.67945 0.3048)
			(end -0.67945 -0.305054)
			(stroke
				(width 0.1)
				(type default)
			)
			(layer "F.Fab")
		)
		(pad "1" smd circle
			(at -0.40005 0 90)
			(size 0 0)
			(layers "F.Cu" "F.Mask" "F.Paste")
			(net "SW_PVDDCR_CPU1_P1_BOOT5")
		)
		(pad "2" smd circle
			(at 0.40005 0 90)
			(size 0 0)
			(layers "F.Cu" "F.Mask" "F.Paste")
			(net "SW_PVDDCR_CPU1_P1_BOOT5_R")
		)
	)
)
